# S9S_MB_2U (Grand Teton) — schematic netlist excerpt (pin names and nets, part order shuffled) for the footprints in the layout excerpt that follows; sources: Cadence DE-HDL packaged netlist, KiCad conversion of 03242023_DA0F0TMBIJ0_F0T_Motherboard_J_brd_V01_OCP.brd

PR4005  Q_RES  30.1K 1% CHIP  pkg 0402LF  page 242 : A = P12V_SCM_IMON ; B = GND
PR3950  Q_RES  100 1% EMPTY  pkg 0402LF  page 193 : A = P12V_E1S_0 ; B = P12V_E1S_AVIN_PD_0
C856  Q_CAP_DIFFBUS  DIFF BUS_0.22UF 6.3V 20% X6S  pkg C0201  page 174 : \1\ = P5E_CPU0_PE1_TX_C_DN<6> ; \2\ = P5E_CPU0_PE1_TX_DN<6>

(kicad_pcb
	(version 20260206)
	(generator "pcbnew")
	(generator_version "10.0")
	(general
		(thickness 1.6)
		(legacy_teardrops no)
	)
	(paper "A4")
	(title_block
		(title "03242023_DA0F0TMBIJ0_F0T_Motherboard_J_brd_V01_OCP.brd")
		(comment 1 "Grand Teton / footprints 1169-1171 of 6105")
	)
	(layers
		(0 "F.Cu" signal "TOP")
		(4 "In1.Cu" signal "GND")
		(6 "In2.Cu" signal "IN1")
		(8 "In3.Cu" signal "GND1")
		(10 "In4.Cu" signal "IN2")
		(12 "In5.Cu" signal "GND2")
		(14 "In6.Cu" signal "IN3")
		(16 "In7.Cu" signal "GND3")
		(18 "In8.Cu" signal "VCC")
		(20 "In9.Cu" signal "VCC1")
		(22 "In10.Cu" signal "GND4")
		(24 "In11.Cu" signal "IN4")
		(26 "In12.Cu" signal "GND5")
		(28 "In13.Cu" signal "IN5")
		(30 "In14.Cu" signal "GND6")
		(32 "In15.Cu" signal "IN6")
		(34 "In16.Cu" signal "GND7")
		(2 "B.Cu" signal "BOTTOM")
		(9 "F.Adhes" user "F.Adhesive")
		(11 "B.Adhes" user "B.Adhesive")
		(13 "F.Paste" user "Package Geometry/Pastemask Top")
		(15 "B.Paste" user "Package Geometry/Pastemask Bottom")
		(5 "F.SilkS" user "Ref Des/Silkscreen Top")
		(7 "B.SilkS" user "Ref Des/Silkscreen Bottom")
		(1 "F.Mask" user "Board Geometry/Soldermask Top")
		(3 "B.Mask" user "Board Geometry/Soldermask Bottom")
		(17 "Dwgs.User" user "User.Drawings")
		(19 "Cmts.User" user "User.Comments")
		(21 "Eco1.User" user "User.Eco1")
		(23 "Eco2.User" user "User.Eco2")
		(25 "Edge.Cuts" user "Board Geometry/Outline")
		(27 "Margin" user)
		(31 "F.CrtYd" user "Package Geometry/Place Bound Top")
		(29 "B.CrtYd" user "Package Geometry/Place Bound Bottom")
		(35 "F.Fab" user "Ref Des/Assembly Top")
		(33 "B.Fab" user "Ref Des/Assembly Bottom")
	)
	(footprint ""
		(layer "F.Cu")
		(at 248.20753 -52.177442 90)
		(property "Reference" "PR3950"
			(at 0 0 90)
			(layer "F.SilkS")
			(hide yes)
			(effects
				(font
					(size 1.27 1.27)
				)
			)
		)
		(property "Value" ""
			(at 0 0 90)
			(layer "F.Fab")
			(effects
				(font
					(size 1.27 1.27)
				)
			)
		)
		(duplicate_pad_numbers_are_jumpers no)
		(fp_line
			(start 0.7874 -0.4064)
			(end 0.7874 0.4064)
			(stroke
				(width 0.1524)
				(type default)
			)
			(layer "F.SilkS")
		)
		(fp_line
			(start -0.7874 -0.4064)
			(end 0.7874 -0.4064)
			(stroke
				(width 0.1524)
				(type default)
			)
			(layer "F.SilkS")
		)
		(fp_line
			(start 0.7874 0.4064)
			(end -0.7874 0.4064)
			(stroke
				(width 0.1524)
				(type default)
			)
			(layer "F.SilkS")
		)
		(fp_line
			(start -0.7874 0.4064)
			(end -0.7874 -0.4064)
			(stroke
				(width 0.1524)
				(type default)
			)
			(layer "F.SilkS")
		)
		(fp_line
			(start -0.12065 -0.305054)
			(end -0.12065 -0.2794)
			(stroke
				(width 0.1)
				(type default)
			)
			(layer "F.Fab")
		)
		(fp_line
			(start -0.67945 -0.305054)
			(end -0.12065 -0.305054)
			(stroke
				(width 0.1)
				(type default)
			)
			(layer "F.Fab")
		)
		(fp_line
			(start 0.67945 -0.3048)
			(end 0.67945 0.3048)
			(stroke
				(width 0.1)
				(type default)
			)
			(layer "F.Fab")
		)
		(fp_line
			(start 0.12065 -0.3048)
			(end 0.67945 -0.3048)
			(stroke
				(width 0.1)
				(type default)
			)
			(layer "F.Fab")
		)
		(fp_line
			(start 0.12065 -0.2794)
			(end 0.12065 -0.3048)
			(stroke
				(width 0.1)
				(type default)
			)
			(layer "F.Fab")
		)
		(fp_line
			(start -0.12065 -0.2794)
			(end 0.12065 -0.2794)
			(stroke
				(width 0.1)
				(type default)
			)
			(layer "F.Fab")
		)
		(fp_line
			(start 0.120396 0.2794)
			(end -0.12065 0.2794)
			(stroke
				(width 0.1)
				(type default)
			)
			(layer "F.Fab")
		)
		(fp_line
			(start -0.12065 0.2794)
			(end -0.12065 0.3048)
			(stroke
				(width 0.1)
				(type default)
			)
			(layer "F.Fab")
		)
		(fp_line
			(start 0.67945 0.3048)
			(end 0.120396 0.3048)
			(stroke
				(width 0.1)
				(type default)
			)
			(layer "F.Fab")
		)
		(fp_line
			(start 0.120396 0.3048)
			(end 0.120396 0.2794)
			(stroke
				(width 0.1)
				(type default)
			)
			(layer "F.Fab")
		)
		(fp_line
			(start -0.12065 0.3048)
			(end -0.67945 0.3048)
			(stroke
				(width 0.1)
				(type default)
			)
			(layer "F.Fab")
		)
		(fp_line
			(start -0.67945 0.3048)
			(end -0.67945 -0.305054)
			(stroke
				(width 0.1)
				(type default)
			)
			(layer "F.Fab")
		)
		(pad "1" smd circle
			(at -0.40005 0 90)
			(size 0 0)
			(layers "F.Cu" "F.Mask" "F.Paste")
			(net "P12V_E1S_0")
		)
		(pad "2" smd circle
			(at 0.40005 0 90)
			(size 0 0)
			(layers "F.Cu" "F.Mask" "F.Paste")
			(net "P12V_E1S_AVIN_PD_0")
		)
	)
	(footprint ""
		(layer "F.Cu")
		(at 173.597062 -32.935672 90)
		(property "Reference" "PR4005"
			(at 0 0 90)
			(layer "F.SilkS")
			(hide yes)
			(effects
				(font
					(size 1.27 1.27)
				)
			)
		)
		(property "Value" ""
			(at 0 0 90)
			(layer "F.Fab")
			(effects
				(font
					(size 1.27 1.27)
				)
			)
		)
		(duplicate_pad_numbers_are_jumpers no)
		(fp_line
			(start 0.7874 -0.4064)
			(end 0.7874 0.4064)
			(stroke
				(width 0.1524)
				(type default)
			)
			(layer "F.SilkS")
		)
		(fp_line
			(start -0.7874 -0.4064)
			(end 0.7874 -0.4064)
			(stroke
				(width 0.1524)
				(type default)
			)
			(layer "F.SilkS")
		)
		(fp_line
			(start 0.7874 0.4064)
			(end -0.7874 0.4064)
			(stroke
				(width 0.1524)
				(type default)
			)
			(layer "F.SilkS")
		)
		(fp_line
			(start -0.7874 0.4064)
			(end -0.7874 -0.4064)
			(stroke
				(width 0.1524)
				(type default)
			)
			(layer "F.SilkS")
		)
		(fp_line
			(start -0.12065 -0.305054)
			(end -0.12065 -0.2794)
			(stroke
				(width 0.1)
				(type default)
			)
			(layer "F.Fab")
		)
		(fp_line
			(start -0.67945 -0.305054)
			(end -0.12065 -0.305054)
			(stroke
				(width 0.1)
				(type default)
			)
			(layer "F.Fab")
		)
		(fp_line
			(start 0.67945 -0.3048)
			(end 0.67945 0.3048)
			(stroke
				(width 0.1)
				(type default)
			)
			(layer "F.Fab")
		)
		(fp_line
			(start 0.12065 -0.3048)
			(end 0.67945 -0.3048)
			(stroke
				(width 0.1)
				(type default)
			)
			(layer "F.Fab")
		)
		(fp_line
			(start 0.12065 -0.2794)
			(end 0.12065 -0.3048)
			(stroke
				(width 0.1)
				(type default)
			)
			(layer "F.Fab")
		)
		(fp_line
			(start -0.12065 -0.2794)
			(end 0.12065 -0.2794)
			(stroke
				(width 0.1)
				(type default)
			)
			(layer "F.Fab")
		)
		(fp_line
			(start 0.120396 0.2794)
			(end -0.12065 0.2794)
			(stroke
				(width 0.1)
				(type default)
			)
			(layer "F.Fab")
		)
		(fp_line
			(start -0.12065 0.2794)
			(end -0.12065 0.3048)
			(stroke
				(width 0.1)
				(type default)
			)
			(layer "F.Fab")
		)
		(fp_line
			(start 0.67945 0.3048)
			(end 0.120396 0.3048)
			(stroke
				(width 0.1)
				(type default)
			)
			(layer "F.Fab")
		)
		(fp_line
			(start 0.120396 0.3048)
			(end 0.120396 0.2794)
			(stroke
				(width 0.1)
				(type default)
			)
			(layer "F.Fab")
		)
		(fp_line
			(start -0.12065 0.3048)
			(end -0.67945 0.3048)
			(stroke
				(width 0.1)
				(type default)
			)
			(layer "F.Fab")
		)
		(fp_line
			(start -0.67945 0.3048)
			(end -0.67945 -0.305054)
			(stroke
				(width 0.1)
				(type default)
			)
			(layer "F.Fab")
		)
		(pad "1" smd circle
			(at -0.40005 0 90)
			(size 0 0)
			(layers "F.Cu" "F.Mask" "F.Paste")
			(net "P12V_SCM_IMON")
		)
		(pad "2" smd circle
			(at 0.40005 0 90)
			(size 0 0)
			(layers "F.Cu" "F.Mask" "F.Paste")
			(net "GND")
		)
	)
	(footprint ""
		(layer "F.Cu")
		(at 415.4678 -17.612614 90)
		(property "Reference" "C856"
			(at 0 0 90)
			(layer "F.SilkS")
			(hide yes)
			(effects
				(font
					(size 1.27 1.27)
				)
			)
		)
		(property "Value" ""
			(at 0 0 90)
			(layer "F.Fab")
			(effects
				(font
					(size 1.27 1.27)
				)
			)
		)
		(duplicate_pad_numbers_are_jumpers no)
		(fp_line
			(start 0.299974 -0.150114)
			(end 0.299974 0.150114)
			(stroke
				(width 0.1)
				(type default)
			)
			(layer "F.Fab")
		)
		(fp_line
			(start -0.299974 -0.150114)
			(end 0.299974 -0.150114)
			(stroke
				(width 0.1)
				(type default)
			)
			(layer "F.Fab")
		)
		(fp_line
			(start 0.299974 0.150114)
			(end -0.299974 0.150114)
			(stroke
				(width 0.1)
				(type default)
			)
			(layer "F.Fab")
		)
		(fp_line
			(start -0.299974 0.150114)
			(end -0.299974 -0.150114)
			(stroke
				(width 0.1)
				(type default)
			)
			(layer "F.Fab")
		)
		(pad "1" smd rect
			(at -0.2667 0 90)
			(size 0.3048 0.381)
			(layers "F.Cu" "F.Mask" "F.Paste")
			(net "P5E_CPU0_PE1_TX_C_DN<6>")
		)
		(pad "2" smd rect
			(at 0.2667 0 90)
			(size 0.3048 0.381)
			(layers "F.Cu" "F.Mask" "F.Paste")
			(net "P5E_CPU0_PE1_TX_DN<6>")
		)
	)
)
